(kicad_pcb
	(version 20241229)
	(generator "pcbnew")
	(generator_version "9.0")
	(general
		(thickness 1.6296)
		(legacy_teardrops no)
	)
	(paper "A3")
	(title_block
		(title "Thunderbolt to 10GbE adapter")
		(date "2026-04-21")
		(rev "1.1.0")
		(company "Antmicro Ltd")
		(comment 1 "www.antmicro.com")
		(comment 9 "footprints 421-425 of 703")
	)
	(layers
		(0 "F.Cu" signal)
		(4 "In1.Cu" signal)
		(6 "In2.Cu" signal)
		(8 "In3.Cu" signal)
		(10 "In4.Cu" signal)
		(12 "In5.Cu" signal)
		(14 "In6.Cu" signal)
		(2 "B.Cu" signal)
		(9 "F.Adhes" user "F.Adhesive")
		(11 "B.Adhes" user "B.Adhesive")
		(13 "F.Paste" user)
		(15 "B.Paste" user)
		(5 "F.SilkS" user "F.Silkscreen")
		(7 "B.SilkS" user "B.Silkscreen")
		(1 "F.Mask" user)
		(3 "B.Mask" user)
		(17 "Dwgs.User" user "User.Drawings")
		(19 "Cmts.User" user "User.Comments")
		(21 "Eco1.User" user "User.Eco1")
		(23 "Eco2.User" user "User.Eco2")
		(25 "Edge.Cuts" user)
		(27 "Margin" user)
		(31 "F.CrtYd" user "F.Courtyard")
		(29 "B.CrtYd" user "B.Courtyard")
		(35 "F.Fab" user)
		(33 "B.Fab" user)
	)
	(footprint "antmicro-footprints:R_0402_1005Metric"
		(layer "B.Cu")
		(at 180.8 74.5)
		(descr "Resistor SMD 0402")
		(tags "resistor SMD 0402")
		(property "Reference" "R86"
			(at 3 0.4 180)
			(layer "B.SilkS")
			(effects
				(font
					(size 0.7 0.7)
					(thickness 0.15)
				)
				(justify left bottom mirror)
			)
		)
		(property "Value" "R_330R_0402"
			(at -1.011843 -1.772047 180)
			(layer "B.Fab")
			(effects
				(font
					(size 0.7 0.7)
					(thickness 0.15)
				)
				(justify left bottom mirror)
			)
		)
		(property "Datasheet" "https://www.bourns.com/docs/product-datasheets/cr.pdf"
			(at 0 0 180)
			(layer "B.Fab")
			(hide yes)
			(effects
				(font
					(size 1.27 1.27)
					(thickness 0.15)
				)
				(justify mirror)
			)
		)
		(property "Description" "SMD Chip Resistor, 330 ohm, ± 1%, 62.5 mW, 0402 [1005 Metric], Thick Film, General Purpose"
			(at 0 0 180)
			(layer "B.Fab")
			(hide yes)
			(effects
				(font
					(size 1.27 1.27)
					(thickness 0.15)
				)
				(justify mirror)
			)
		)
		(property "MPN" "CR0402-FX-3300GLF"
			(at 0 0 0)
			(unlocked yes)
			(layer "B.Fab")
			(hide yes)
			(effects
				(font
					(size 1 1)
					(thickness 0.15)
				)
				(justify mirror)
			)
		)
		(property "Manufacturer" "Bourns"
			(at 0 0 0)
			(unlocked yes)
			(layer "B.Fab")
			(hide yes)
			(effects
				(font
					(size 1 1)
					(thickness 0.15)
				)
				(justify mirror)
			)
		)
		(property "License" "Apache-2.0"
			(at 0 0 0)
			(unlocked yes)
			(layer "B.Fab")
			(hide yes)
			(effects
				(font
					(size 1 1)
					(thickness 0.15)
				)
				(justify mirror)
			)
		)
		(property "Author" "Antmicro"
			(at 0 0 0)
			(unlocked yes)
			(layer "B.Fab")
			(hide yes)
			(effects
				(font
					(size 1 1)
					(thickness 0.15)
				)
				(justify mirror)
			)
		)
		(property "Val" "330R"
			(at 0 0 0)
			(unlocked yes)
			(layer "B.Fab")
			(hide yes)
			(effects
				(font
					(size 1 1)
					(thickness 0.15)
				)
				(justify mirror)
			)
		)
		(property "Tolerance" "1%"
			(at 0 0 0)
			(unlocked yes)
			(layer "B.Fab")
			(hide yes)
			(effects
				(font
					(size 1 1)
					(thickness 0.15)
				)
				(justify mirror)
			)
		)
		(sheetname "/X710 DCDC converters/")
		(sheetfile "DCDC_converters_X710.kicad_sch")
		(attr smd)
		(fp_rect
			(start -0.925 0.47)
			(end 0.925 -0.47)
			(stroke
				(width 0.05)
				(type default)
			)
			(fill no)
			(layer "B.CrtYd")
		)
		(fp_rect
			(start -0.5 0.25)
			(end 0.5 -0.25)
			(stroke
				(width 0.15)
				(type solid)
			)
			(fill no)
			(layer "B.Fab")
		)
		(fp_text user "License: Apache-2.0"
			(at -0.95 -5.169 180)
			(layer "B.Fab")
			(effects
				(font
					(size 0.7 0.7)
					(thickness 0.15)
				)
				(justify left bottom mirror)
			)
		)
		(fp_text user "${REFERENCE}"
			(at -0.95 -3.168 180)
			(layer "B.Fab")
			(effects
				(font
					(size 0.7 0.7)
					(thickness 0.15)
				)
				(justify left bottom mirror)
			)
		)
		(fp_text user "Author: Antmicro"
			(at -0.95 -4.169 180)
			(layer "B.Fab")
			(effects
				(font
					(size 0.7 0.7)
					(thickness 0.15)
				)
				(justify left bottom mirror)
			)
		)
		(pad "1" smd roundrect
			(at -0.48 0)
			(size 0.59 0.64)
			(layers "B.Cu" "B.Mask" "B.Paste")
			(roundrect_rratio 0.25)
			(net 430 "Net-(Q4-C)")
			(pintype "passive")
		)
		(pad "2" smd roundrect
			(at 0.48 0)
			(size 0.59 0.64)
			(layers "B.Cu" "B.Mask" "B.Paste")
			(roundrect_rratio 0.25)
			(net 416 "Net-(D9-C)")
			(pintype "passive")
		)
	)
	(footprint "antmicro-footprints:C_0402_1005Metric"
		(layer "B.Cu")
		(at 149.331866 81.260117 180)
		(descr "Capacitor SMD 0402")
		(tags "capacitor SMD 0402")
		(property "Reference" "C219"
			(at -19.468135 -9.464883 0)
			(layer "B.SilkS")
			(effects
				(font
					(size 0.7 0.7)
					(thickness 0.15)
				)
				(justify mirror)
			)
		)
		(property "Value" "C_1u_25V_0402"
			(at -1.022927 -2.155213 0)
			(layer "B.Fab")
			(effects
				(font
					(size 0.7 0.7)
					(thickness 0.15)
				)
				(justify left bottom mirror)
			)
		)
		(property "Datasheet" "https://www.murata.com/products/productdetail?partno=GRM155R61E105KE11%23"
			(at 0 0 0)
			(layer "B.Fab")
			(hide yes)
			(effects
				(font
					(size 1.27 1.27)
					(thickness 0.15)
				)
				(justify mirror)
			)
		)
		(property "Description" "SMD Multilayer Ceramic Capacitor, 1 µF, 25 V, 0402 [1005 Metric], ± 10%, X5R, GRM Series"
			(at 0 0 0)
			(layer "B.Fab")
			(hide yes)
			(effects
				(font
					(size 1.27 1.27)
					(thickness 0.15)
				)
				(justify mirror)
			)
		)
		(property "MPN" "GRM155R61E105KE11J"
			(at 0 0 180)
			(unlocked yes)
			(layer "B.Fab")
			(hide yes)
			(effects
				(font
					(size 1 1)
					(thickness 0.15)
				)
				(justify mirror)
			)
		)
		(property "Manufacturer" "Murata"
			(at 0 0 180)
			(unlocked yes)
			(layer "B.Fab")
			(hide yes)
			(effects
				(font
					(size 1 1)
					(thickness 0.15)
				)
				(justify mirror)
			)
		)
		(property "License" "Apache-2.0"
			(at 0 0 180)
			(unlocked yes)
			(layer "B.Fab")
			(hide yes)
			(effects
				(font
					(size 1 1)
					(thickness 0.15)
				)
				(justify mirror)
			)
		)
		(property "Author" "Antmicro"
			(at 0 0 180)
			(unlocked yes)
			(layer "B.Fab")
			(hide yes)
			(effects
				(font
					(size 1 1)
					(thickness 0.15)
				)
				(justify mirror)
			)
		)
		(property "Val" "1u"
			(at 0 0 180)
			(unlocked yes)
			(layer "B.Fab")
			(hide yes)
			(effects
				(font
					(size 1 1)
					(thickness 0.15)
				)
				(justify mirror)
			)
		)
		(property "Voltage" "25V"
			(at 0 0 180)
			(unlocked yes)
			(layer "B.Fab")
			(hide yes)
			(effects
				(font
					(size 1 1)
					(thickness 0.15)
				)
				(justify mirror)
			)
		)
		(property "Dielectric" "X5R"
			(at 0 0 180)
			(unlocked yes)
			(layer "B.Fab")
			(hide yes)
			(effects
				(font
					(size 1 1)
					(thickness 0.15)
				)
				(justify mirror)
			)
		)
		(sheetname "/X710-AT2 power/")
		(sheetfile "x710-at2-power.kicad_sch")
		(attr smd)
		(fp_rect
			(start -0.925 0.47)
			(end 0.925 -0.47)
			(stroke
				(width 0.05)
				(type default)
			)
			(fill no)
			(layer "B.CrtYd")
		)
		(fp_line
			(start 0.504 0.25)
			(end 0.504 -0.248)
			(stroke
				(width 0.15)
				(type solid)
			)
			(layer "B.Fab")
		)
		(fp_line
			(start 0.504 -0.248)
			(end -0.494 -0.248)
			(stroke
				(width 0.15)
				(type solid)
			)
			(layer "B.Fab")
		)
		(fp_line
			(start -0.494 0.25)
			(end 0.504 0.25)
			(stroke
				(width 0.15)
				(type solid)
			)
			(layer "B.Fab")
		)
		(fp_line
			(start -0.494 -0.248)
			(end -0.494 0.25)
			(stroke
				(width 0.15)
				(type solid)
			)
			(layer "B.Fab")
		)
		(fp_text user "${REFERENCE}"
			(at -0.939 -4.599 0)
			(layer "B.Fab")
			(effects
				(font
					(size 0.7 0.7)
					(thickness 0.15)
				)
				(justify left bottom mirror)
			)
		)
		(fp_text user "Author: Antmicro"
			(at -0.939 -3.399 0)
			(layer "B.Fab")
			(effects
				(font
					(size 0.7 0.7)
					(thickness 0.15)
				)
				(justify left bottom mirror)
			)
		)
		(fp_text user "License: Apache-2.0"
			(at -0.939 -5.799 0)
			(layer "B.Fab")
			(effects
				(font
					(size 0.7 0.7)
					(thickness 0.15)
				)
				(justify left bottom mirror)
			)
		)
		(pad "1" smd roundrect
			(at -0.48 0 180)
			(size 0.59 0.64)
			(layers "B.Cu" "B.Mask" "B.Paste")
			(roundrect_rratio 0.25)
			(net 23 "GND")
			(pintype "passive")
		)
		(pad "2" smd roundrect
			(at 0.48 0 180)
			(size 0.59 0.64)
			(layers "B.Cu" "B.Mask" "B.Paste")
			(roundrect_rratio 0.25)
			(net 9 "VCCD")
			(pintype "passive")
		)
	)
	(footprint "antmicro-footprints:C_0402_1005Metric"
		(layer "B.Cu")
		(at 156.111865 84.205116 180)
		(descr "Capacitor SMD 0402")
		(tags "capacitor SMD 0402")
		(property "Reference" "C202"
			(at -19.873134 -9.464883 0)
			(layer "B.SilkS")
			(effects
				(font
					(size 0.7 0.7)
					(thickness 0.15)
				)
				(justify mirror)
			)
		)
		(property "Value" "C_1u_25V_0402"
			(at -1.022927 -2.155213 0)
			(layer "B.Fab")
			(effects
				(font
					(size 0.7 0.7)
					(thickness 0.15)
				)
				(justify left bottom mirror)
			)
		)
		(property "Datasheet" "https://www.murata.com/products/productdetail?partno=GRM155R61E105KE11%23"
			(at 0 0 0)
			(layer "B.Fab")
			(hide yes)
			(effects
				(font
					(size 1.27 1.27)
					(thickness 0.15)
				)
				(justify mirror)
			)
		)
		(property "Description" "SMD Multilayer Ceramic Capacitor, 1 µF, 25 V, 0402 [1005 Metric], ± 10%, X5R, GRM Series"
			(at 0 0 0)
			(layer "B.Fab")
			(hide yes)
			(effects
				(font
					(size 1.27 1.27)
					(thickness 0.15)
				)
				(justify mirror)
			)
		)
		(property "MPN" "GRM155R61E105KE11J"
			(at 0 0 180)
			(unlocked yes)
			(layer "B.Fab")
			(hide yes)
			(effects
				(font
					(size 1 1)
					(thickness 0.15)
				)
				(justify mirror)
			)
		)
		(property "Manufacturer" "Murata"
			(at 0 0 180)
			(unlocked yes)
			(layer "B.Fab")
			(hide yes)
			(effects
				(font
					(size 1 1)
					(thickness 0.15)
				)
				(justify mirror)
			)
		)
		(property "License" "Apache-2.0"
			(at 0 0 180)
			(unlocked yes)
			(layer "B.Fab")
			(hide yes)
			(effects
				(font
					(size 1 1)
					(thickness 0.15)
				)
				(justify mirror)
			)
		)
		(property "Author" "Antmicro"
			(at 0 0 180)
			(unlocked yes)
			(layer "B.Fab")
			(hide yes)
			(effects
				(font
					(size 1 1)
					(thickness 0.15)
				)
				(justify mirror)
			)
		)
		(property "Val" "1u"
			(at 0 0 180)
			(unlocked yes)
			(layer "B.Fab")
			(hide yes)
			(effects
				(font
					(size 1 1)
					(thickness 0.15)
				)
				(justify mirror)
			)
		)
		(property "Voltage" "25V"
			(at 0 0 180)
			(unlocked yes)
			(layer "B.Fab")
			(hide yes)
			(effects
				(font
					(size 1 1)
					(thickness 0.15)
				)
				(justify mirror)
			)
		)
		(property "Dielectric" "X5R"
			(at 0 0 180)
			(unlocked yes)
			(layer "B.Fab")
			(hide yes)
			(effects
				(font
					(size 1 1)
					(thickness 0.15)
				)
				(justify mirror)
			)
		)
		(sheetname "/X710-AT2 power/")
		(sheetfile "x710-at2-power.kicad_sch")
		(attr smd)
		(fp_rect
			(start -0.925 0.47)
			(end 0.925 -0.47)
			(stroke
				(width 0.05)
				(type default)
			)
			(fill no)
			(layer "B.CrtYd")
		)
		(fp_line
			(start 0.504 0.25)
			(end 0.504 -0.248)
			(stroke
				(width 0.15)
				(type solid)
			)
			(layer "B.Fab")
		)
		(fp_line
			(start 0.504 -0.248)
			(end -0.494 -0.248)
			(stroke
				(width 0.15)
				(type solid)
			)
			(layer "B.Fab")
		)
		(fp_line
			(start -0.494 0.25)
			(end 0.504 0.25)
			(stroke
				(width 0.15)
				(type solid)
			)
			(layer "B.Fab")
		)
		(fp_line
			(start -0.494 -0.248)
			(end -0.494 0.25)
			(stroke
				(width 0.15)
				(type solid)
			)
			(layer "B.Fab")
		)
		(fp_text user "Author: Antmicro"
			(at -0.939 -3.399 0)
			(layer "B.Fab")
			(effects
				(font
					(size 0.7 0.7)
					(thickness 0.15)
				)
				(justify left bottom mirror)
			)
		)
		(fp_text user "${REFERENCE}"
			(at -0.939 -4.599 0)
			(layer "B.Fab")
			(effects
				(font
					(size 0.7 0.7)
					(thickness 0.15)
				)
				(justify left bottom mirror)
			)
		)
		(fp_text user "License: Apache-2.0"
			(at -0.939 -5.799 0)
			(layer "B.Fab")
			(effects
				(font
					(size 0.7 0.7)
					(thickness 0.15)
				)
				(justify left bottom mirror)
			)
		)
		(pad "1" smd roundrect
			(at -0.48 0 180)
			(size 0.59 0.64)
			(layers "B.Cu" "B.Mask" "B.Paste")
			(roundrect_rratio 0.25)
			(net 23 "GND")
			(pintype "passive")
		)
		(pad "2" smd roundrect
			(at 0.48 0 180)
			(size 0.59 0.64)
			(layers "B.Cu" "B.Mask" "B.Paste")
			(roundrect_rratio 0.25)
			(net 6 "DVDD")
			(pintype "passive")
		)
	)
	(footprint "antmicro-footprints:C_0402_1005Metric"
		(layer "B.Cu")
		(at 163.25 133.25)
		(descr "Capacitor SMD 0402")
		(tags "capacitor SMD 0402")
		(property "Reference" "C290"
			(at 4.5 -2.75 180)
			(layer "B.SilkS")
			(effects
				(font
					(size 0.7 0.7)
					(thickness 0.15)
				)
				(justify left bottom mirror)
			)
		)
		(property "Value" "C_1u_25V_0402"
			(at -1.022927 -2.155213 180)
			(layer "B.Fab")
			(effects
				(font
					(size 0.7 0.7)
					(thickness 0.15)
				)
				(justify left bottom mirror)
			)
		)
		(property "Datasheet" "https://www.murata.com/products/productdetail?partno=GRM155R61E105KE11%23"
			(at 0 0 180)
			(layer "B.Fab")
			(hide yes)
			(effects
				(font
					(size 1.27 1.27)
					(thickness 0.15)
				)
				(justify mirror)
			)
		)
		(property "Description" "SMD Multilayer Ceramic Capacitor, 1 µF, 25 V, 0402 [1005 Metric], ± 10%, X5R, GRM Series"
			(at 0 0 180)
			(layer "B.Fab")
			(hide yes)
			(effects
				(font
					(size 1.27 1.27)
					(thickness 0.15)
				)
				(justify mirror)
			)
		)
		(property "MPN" "GRM155R61E105KE11J"
			(at 0 0 0)
			(unlocked yes)
			(layer "B.Fab")
			(hide yes)
			(effects
				(font
					(size 1 1)
					(thickness 0.15)
				)
				(justify mirror)
			)
		)
		(property "Manufacturer" "Murata"
			(at 0 0 0)
			(unlocked yes)
			(layer "B.Fab")
			(hide yes)
			(effects
				(font
					(size 1 1)
					(thickness 0.15)
				)
				(justify mirror)
			)
		)
		(property "License" "Apache-2.0"
			(at 0 0 0)
			(unlocked yes)
			(layer "B.Fab")
			(hide yes)
			(effects
				(font
					(size 1 1)
					(thickness 0.15)
				)
				(justify mirror)
			)
		)
		(property "Author" "Antmicro"
			(at 0 0 0)
			(unlocked yes)
			(layer "B.Fab")
			(hide yes)
			(effects
				(font
					(size 1 1)
					(thickness 0.15)
				)
				(justify mirror)
			)
		)
		(property "Val" "1u"
			(at 0 0 0)
			(unlocked yes)
			(layer "B.Fab")
			(hide yes)
			(effects
				(font
					(size 1 1)
					(thickness 0.15)
				)
				(justify mirror)
			)
		)
		(property "Voltage" "25V"
			(at 0 0 0)
			(unlocked yes)
			(layer "B.Fab")
			(hide yes)
			(effects
				(font
					(size 1 1)
					(thickness 0.15)
				)
				(justify mirror)
			)
		)
		(property "Dielectric" "X5R"
			(at 0 0 0)
			(unlocked yes)
			(layer "B.Fab")
			(hide yes)
			(effects
				(font
					(size 1 1)
					(thickness 0.15)
				)
				(justify mirror)
			)
		)
		(sheetname "/2xRJ45/")
		(sheetfile "2xrj45.kicad_sch")
		(attr smd)
		(fp_rect
			(start -0.925 0.47)
			(end 0.925 -0.47)
			(stroke
				(width 0.05)
				(type default)
			)
			(fill no)
			(layer "B.CrtYd")
		)
		(fp_line
			(start -0.494 -0.248)
			(end -0.494 0.25)
			(stroke
				(width 0.15)
				(type solid)
			)
			(layer "B.Fab")
		)
		(fp_line
			(start -0.494 0.25)
			(end 0.504 0.25)
			(stroke
				(width 0.15)
				(type solid)
			)
			(layer "B.Fab")
		)
		(fp_line
			(start 0.504 -0.248)
			(end -0.494 -0.248)
			(stroke
				(width 0.15)
				(type solid)
			)
			(layer "B.Fab")
		)
		(fp_line
			(start 0.504 0.25)
			(end 0.504 -0.248)
			(stroke
				(width 0.15)
				(type solid)
			)
			(layer "B.Fab")
		)
		(fp_text user "License: Apache-2.0"
			(at -0.939 -5.799 180)
			(layer "B.Fab")
			(effects
				(font
					(size 0.7 0.7)
					(thickness 0.15)
				)
				(justify left bottom mirror)
			)
		)
		(fp_text user "Author: Antmicro"
			(at -0.939 -3.399 180)
			(layer "B.Fab")
			(effects
				(font
					(size 0.7 0.7)
					(thickness 0.15)
				)
				(justify left bottom mirror)
			)
		)
		(fp_text user "${REFERENCE}"
			(at -0.939 -4.599 180)
			(layer "B.Fab")
			(effects
				(font
					(size 0.7 0.7)
					(thickness 0.15)
				)
				(justify left bottom mirror)
			)
		)
		(pad "1" smd roundrect
			(at -0.48 0)
			(size 0.59 0.64)
			(layers "B.Cu" "B.Mask" "B.Paste")
			(roundrect_rratio 0.25)
			(net 23 "GND")
			(pintype "passive")
		)
		(pad "2" smd roundrect
			(at 0.48 0)
			(size 0.59 0.64)
			(layers "B.Cu" "B.Mask" "B.Paste")
			(roundrect_rratio 0.25)
			(net 135 "+1V88_CT")
			(pintype "passive")
		)
	)
	(footprint "antmicro-footprints:TP_SMD_0.75mm"
		(layer "B.Cu")
		(at 136.25 57.75 90)
		(property "Reference" "TP39"
			(at 3.15 0.45 270)
			(layer "B.SilkS")
			(effects
				(font
					(size 0.7 0.7)
					(thickness 0.15)
				)
				(justify left bottom mirror)
			)
		)
		(property "Value" "TP_0.75mm_SMD"
			(at 0 -1.2 270)
			(layer "B.Fab")
			(effects
				(font
					(size 0.7 0.7)
					(thickness 0.15)
				)
				(justify left bottom mirror)
			)
		)
		(property "Description" "SMT test point"
			(at 0 0 270)
			(layer "B.Fab")
			(hide yes)
			(effects
				(font
					(size 1.27 1.27)
					(thickness 0.15)
				)
				(justify mirror)
			)
		)
		(property "MPN" ""
			(at 0 0 90)
			(unlocked yes)
			(layer "B.Fab")
			(hide yes)
			(effects
				(font
					(size 1 1)
					(thickness 0.15)
				)
				(justify mirror)
			)
		)
		(property "Manufacturer" ""
			(at 0 0 90)
			(unlocked yes)
			(layer "B.Fab")
			(hide yes)
			(effects
				(font
					(size 1 1)
					(thickness 0.15)
				)
				(justify mirror)
			)
		)
		(property "Author" "Antmicro"
			(at 0 0 90)
			(unlocked yes)
			(layer "B.Fab")
			(hide yes)
			(effects
				(font
					(size 1 1)
					(thickness 0.15)
				)
				(justify mirror)
			)
		)
		(property "License" "Apache-2.0"
			(at 0 0 90)
			(unlocked yes)
			(layer "B.Fab")
			(hide yes)
			(effects
				(font
					(size 1 1)
					(thickness 0.15)
				)
				(justify mirror)
			)
		)
		(sheetname "/Power input/")
		(sheetfile "power_input.kicad_sch")
		(attr exclude_from_pos_files exclude_from_bom)
		(fp_circle
			(center 0 0)
			(end 0.475 0)
			(stroke
				(width 0.05)
				(type default)
			)
			(fill no)
			(layer "B.CrtYd")
		)
		(fp_text user "Author: Antmicro"
			(at -0.4 -3.901 270)
			(layer "B.Fab")
			(effects
				(font
					(size 0.7 0.7)
					(thickness 0.15)
				)
				(justify left bottom mirror)
			)
		)
		(fp_text user "License: Apache-2.0"
			(at -0.4 -5.101 270)
			(layer "B.Fab")
			(effects
				(font
					(size 0.7 0.7)
					(thickness 0.15)
				)
				(justify left bottom mirror)
			)
		)
		(fp_text user "${REFERENCE}"
			(at -0.4 -2.7 270)
			(layer "B.Fab")
			(effects
				(font
					(size 0.7 0.7)
					(thickness 0.15)
				)
				(justify left bottom mirror)
			)
		)
		(pad "1" smd circle
			(at 0 0 90)
			(size 0.75 0.75)
			(layers "B.Cu" "B.Mask")
			(net 13 "/Power input/5V_JACK")
			(pinfunction "1")
			(pintype "passive")
		)
	)
)
